# S9S_MB_2U (Grand Teton) — schematic netlist excerpt (pin names and nets, part order shuffled) for the footprints in the layout excerpt that follows; sources: Cadence DE-HDL packaged netlist, KiCad conversion of 03242023_DA0F0TMBIJ0_F0T_Motherboard_J_brd_V01_OCP.brd

Q34  MOSFET_NCH_GDS_ESD_PROTECTED  2N7002K IC  pkg SOT23_GDSXC  page 185
  D  = RST_RTCRST_N
  G  = RST_PFR_OVR_RTC
  S  = GND

C427  Q_CAP  22UF 4V 20% X6S  pkg C0402  page 77 : A = PVCCD_HV_CPU1 ; B = GND

(kicad_pcb
	(version 20260206)
	(generator "pcbnew")
	(generator_version "10.0")
	(general
		(thickness 1.6)
		(legacy_teardrops no)
	)
	(paper "A4")
	(title_block
		(title "03242023_DA0F0TMBIJ0_F0T_Motherboard_J_brd_V01_OCP.brd")
		(comment 1 "Grand Teton / footprints 25-26 of 6105")
	)
	(layers
		(0 "F.Cu" signal "TOP")
		(4 "In1.Cu" signal "GND")
		(6 "In2.Cu" signal "IN1")
		(8 "In3.Cu" signal "GND1")
		(10 "In4.Cu" signal "IN2")
		(12 "In5.Cu" signal "GND2")
		(14 "In6.Cu" signal "IN3")
		(16 "In7.Cu" signal "GND3")
		(18 "In8.Cu" signal "VCC")
		(20 "In9.Cu" signal "VCC1")
		(22 "In10.Cu" signal "GND4")
		(24 "In11.Cu" signal "IN4")
		(26 "In12.Cu" signal "GND5")
		(28 "In13.Cu" signal "IN5")
		(30 "In14.Cu" signal "GND6")
		(32 "In15.Cu" signal "IN6")
		(34 "In16.Cu" signal "GND7")
		(2 "B.Cu" signal "BOTTOM")
		(9 "F.Adhes" user "F.Adhesive")
		(11 "B.Adhes" user "B.Adhesive")
		(13 "F.Paste" user "Package Geometry/Pastemask Top")
		(15 "B.Paste" user "Package Geometry/Pastemask Bottom")
		(5 "F.SilkS" user "Ref Des/Silkscreen Top")
		(7 "B.SilkS" user "Ref Des/Silkscreen Bottom")
		(1 "F.Mask" user "Board Geometry/Soldermask Top")
		(3 "B.Mask" user "Board Geometry/Soldermask Bottom")
		(17 "Dwgs.User" user "User.Drawings")
		(19 "Cmts.User" user "User.Comments")
		(21 "Eco1.User" user "User.Eco1")
		(23 "Eco2.User" user "User.Eco2")
		(25 "Edge.Cuts" user "Board Geometry/Outline")
		(27 "Margin" user)
		(31 "F.CrtYd" user "Package Geometry/Place Bound Top")
		(29 "B.CrtYd" user "Package Geometry/Place Bound Bottom")
		(35 "F.Fab" user "Ref Des/Assembly Top")
		(33 "B.Fab" user "Ref Des/Assembly Bottom")
	)
	(footprint ""
		(layer "F.Cu")
		(at 205.968092 -101.006656)
		(property "Reference" "Q34"
			(at -3.937 -1.92913 0)
			(unlocked yes)
			(layer "F.SilkS")
			(effects
				(font
					(size 0.7874 0.5842)
					(thickness 0.1524)
				)
				(justify left)
			)
		)
		(property "Value" ""
			(at 0 0 0)
			(layer "F.Fab")
			(effects
				(font
					(size 1.27 1.27)
				)
			)
		)
		(duplicate_pad_numbers_are_jumpers no)
		(fp_line
			(start -1.603248 -1.500124)
			(end 1.603248 -1.500124)
			(stroke
				(width 0.1524)
				(type default)
			)
			(layer "F.SilkS")
		)
		(fp_line
			(start -1.603248 1.500124)
			(end -1.603248 -1.500124)
			(stroke
				(width 0.1524)
				(type default)
			)
			(layer "F.SilkS")
		)
		(fp_line
			(start 1.603248 -1.500124)
			(end 1.603248 1.500124)
			(stroke
				(width 0.1524)
				(type default)
			)
			(layer "F.SilkS")
		)
		(fp_line
			(start 1.603248 1.500124)
			(end -1.603248 1.500124)
			(stroke
				(width 0.1524)
				(type default)
			)
			(layer "F.SilkS")
		)
		(fp_line
			(start -1.249934 -1.169924)
			(end -1.249934 -0.729996)
			(stroke
				(width 0.1)
				(type default)
			)
			(layer "F.Fab")
		)
		(fp_line
			(start -1.249934 -0.729996)
			(end -0.6985 -0.729996)
			(stroke
				(width 0.1)
				(type default)
			)
			(layer "F.Fab")
		)
		(fp_line
			(start -1.249934 0.729996)
			(end -1.249934 1.169924)
			(stroke
				(width 0.1)
				(type default)
			)
			(layer "F.Fab")
		)
		(fp_line
			(start -1.249934 1.169924)
			(end -0.700024 1.169924)
			(stroke
				(width 0.1)
				(type default)
			)
			(layer "F.Fab")
		)
		(fp_line
			(start -0.700024 -1.500124)
			(end -0.700024 -1.169924)
			(stroke
				(width 0.1)
				(type default)
			)
			(layer "F.Fab")
		)
		(fp_line
			(start -0.700024 -1.169924)
			(end -1.249934 -1.169924)
			(stroke
				(width 0.1)
				(type default)
			)
			(layer "F.Fab")
		)
		(fp_line
			(start -0.700024 1.169924)
			(end -0.700024 1.500124)
			(stroke
				(width 0.1)
				(type default)
			)
			(layer "F.Fab")
		)
		(fp_line
			(start -0.700024 1.500124)
			(end 0.700024 1.500124)
			(stroke
				(width 0.1)
				(type default)
			)
			(layer "F.Fab")
		)
		(fp_line
			(start -0.6985 -0.729996)
			(end -0.6985 0.729996)
			(stroke
				(width 0.1)
				(type default)
			)
			(layer "F.Fab")
		)
		(fp_line
			(start -0.6985 0.729996)
			(end -1.249934 0.729996)
			(stroke
				(width 0.1)
				(type default)
			)
			(layer "F.Fab")
		)
		(fp_line
			(start 0.700024 -1.500124)
			(end -0.700024 -1.500124)
			(stroke
				(width 0.1)
				(type default)
			)
			(layer "F.Fab")
		)
		(fp_line
			(start 0.700024 -0.219964)
			(end 0.700024 -1.500124)
			(stroke
				(width 0.1)
				(type default)
			)
			(layer "F.Fab")
		)
		(fp_line
			(start 0.700024 0.219964)
			(end 1.249934 0.219964)
			(stroke
				(width 0.1)
				(type default)
			)
			(layer "F.Fab")
		)
		(fp_line
			(start 0.700024 1.500124)
			(end 0.700024 0.219964)
			(stroke
				(width 0.1)
				(type default)
			)
			(layer "F.Fab")
		)
		(fp_line
			(start 1.249934 -0.219964)
			(end 0.700024 -0.219964)
			(stroke
				(width 0.1)
				(type default)
			)
			(layer "F.Fab")
		)
		(fp_line
			(start 1.249934 0.219964)
			(end 1.249934 -0.219964)
			(stroke
				(width 0.1)
				(type default)
			)
			(layer "F.Fab")
		)
		(fp_rect
			(start -0.700024 1.500124)
			(end 0.700024 -1.500124)
			(stroke
				(width 0)
				(type default)
			)
			(fill no)
			(layer "F.Fab")
		)
		(pad "D" smd rect
			(at 0.999998 0 270)
			(size 0.8128 0.9144)
			(layers "F.Cu" "F.Mask" "F.Paste")
			(net "RST_RTCRST_N")
		)
		(pad "G" smd rect
			(at -0.999998 -0.94996 270)
			(size 0.8128 0.9144)
			(layers "F.Cu" "F.Mask" "F.Paste")
			(net "RST_PFR_OVR_RTC")
		)
		(pad "S" smd rect
			(at -0.999998 0.94996 270)
			(size 0.8128 0.9144)
			(layers "F.Cu" "F.Mask" "F.Paste")
			(net "GND")
		)
	)
	(footprint ""
		(layer "F.Cu")
		(at 119.508016 -247.715278 90)
		(property "Reference" "C427"
			(at 0 0 90)
			(layer "F.SilkS")
			(hide yes)
			(effects
				(font
					(size 1.27 1.27)
				)
			)
		)
		(property "Value" ""
			(at 0 0 90)
			(layer "F.Fab")
			(effects
				(font
					(size 1.27 1.27)
				)
			)
		)
		(duplicate_pad_numbers_are_jumpers no)
		(fp_line
			(start 0.7874 -0.4064)
			(end 0.7874 0.4064)
			(stroke
				(width 0.1524)
				(type default)
			)
			(layer "F.SilkS")
		)
		(fp_line
			(start -0.7874 -0.4064)
			(end 0.7874 -0.4064)
			(stroke
				(width 0.1524)
				(type default)
			)
			(layer "F.SilkS")
		)
		(fp_line
			(start 0.7874 0.4064)
			(end -0.7874 0.4064)
			(stroke
				(width 0.1524)
				(type default)
			)
			(layer "F.SilkS")
		)
		(fp_line
			(start -0.7874 0.4064)
			(end -0.7874 -0.4064)
			(stroke
				(width 0.1524)
				(type default)
			)
			(layer "F.SilkS")
		)
		(fp_line
			(start -0.12065 -0.305054)
			(end -0.12065 -0.2794)
			(stroke
				(width 0.1)
				(type default)
			)
			(layer "F.Fab")
		)
		(fp_line
			(start -0.67945 -0.305054)
			(end -0.12065 -0.305054)
			(stroke
				(width 0.1)
				(type default)
			)
			(layer "F.Fab")
		)
		(fp_line
			(start 0.67945 -0.3048)
			(end 0.67945 0.3048)
			(stroke
				(width 0.1)
				(type default)
			)
			(layer "F.Fab")
		)
		(fp_line
			(start 0.12065 -0.3048)
			(end 0.67945 -0.3048)
			(stroke
				(width 0.1)
				(type default)
			)
			(layer "F.Fab")
		)
		(fp_line
			(start 0.12065 -0.2794)
			(end 0.12065 -0.3048)
			(stroke
				(width 0.1)
				(type default)
			)
			(layer "F.Fab")
		)
		(fp_line
			(start -0.12065 -0.2794)
			(end 0.12065 -0.2794)
			(stroke
				(width 0.1)
				(type default)
			)
			(layer "F.Fab")
		)
		(fp_line
			(start 0.120396 0.2794)
			(end -0.12065 0.2794)
			(stroke
				(width 0.1)
				(type default)
			)
			(layer "F.Fab")
		)
		(fp_line
			(start -0.12065 0.2794)
			(end -0.12065 0.3048)
			(stroke
				(width 0.1)
				(type default)
			)
			(layer "F.Fab")
		)
		(fp_line
			(start 0.67945 0.3048)
			(end 0.120396 0.3048)
			(stroke
				(width 0.1)
				(type default)
			)
			(layer "F.Fab")
		)
		(fp_line
			(start 0.120396 0.3048)
			(end 0.120396 0.2794)
			(stroke
				(width 0.1)
				(type default)
			)
			(layer "F.Fab")
		)
		(fp_line
			(start -0.12065 0.3048)
			(end -0.67945 0.3048)
			(stroke
				(width 0.1)
				(type default)
			)
			(layer "F.Fab")
		)
		(fp_line
			(start -0.67945 0.3048)
			(end -0.67945 -0.305054)
			(stroke
				(width 0.1)
				(type default)
			)
			(layer "F.Fab")
		)
		(pad "1" smd circle
			(at -0.40005 0 90)
			(size 0 0)
			(layers "F.Cu" "F.Mask" "F.Paste")
			(net "PVCCD_HV_CPU1")
		)
		(pad "2" smd circle
			(at 0.40005 0 90)
			(size 0 0)
			(layers "F.Cu" "F.Mask" "F.Paste")
			(net "GND")
		)
	)
)
